(kicad_pcb
	(version 20260206)
	(generator "pcbnew")
	(generator_version "10.0")
	(general
		(thickness 1.6)
		(legacy_teardrops no)
	)
	(paper "A4")
	(title_block
		(title "Bryce Canyon_R.DPB_16317-1_OCP.brd")
		(comment 1 "Bryce Canyon / footprints 1777-1784 of 2099")
	)
	(layers
		(0 "F.Cu" signal "TOP")
		(4 "In1.Cu" signal "L2GND")
		(6 "In2.Cu" signal "L3")
		(8 "In3.Cu" signal "L4VCC")
		(10 "In4.Cu" signal "L5VCC")
		(12 "In5.Cu" signal "L6")
		(14 "In6.Cu" signal "L7GND")
		(2 "B.Cu" signal "BOTTOM")
		(9 "F.Adhes" user "F.Adhesive")
		(11 "B.Adhes" user "B.Adhesive")
		(13 "F.Paste" user "Package Geometry/Pastemask Top")
		(15 "B.Paste" user "Package Geometry/Pastemask Bottom")
		(5 "F.SilkS" user "Ref Des/Silkscreen Top")
		(7 "B.SilkS" user "Ref Des/Silkscreen Bottom")
		(1 "F.Mask" user "Board Geometry/Soldermask Top")
		(3 "B.Mask" user "Board Geometry/Soldermask Bottom")
		(17 "Dwgs.User" user "User.Drawings")
		(19 "Cmts.User" user "User.Comments")
		(21 "Eco1.User" user "User.Eco1")
		(23 "Eco2.User" user "User.Eco2")
		(25 "Edge.Cuts" user "Board Geometry/Outline")
		(27 "Margin" user)
		(31 "F.CrtYd" user "Package Geometry/Place Bound Top")
		(29 "B.CrtYd" user "Package Geometry/Place Bound Bottom")
		(35 "F.Fab" user "Ref Des/Assembly Top")
		(33 "B.Fab" user "Ref Des/Assembly Bottom")
	)
	(footprint ""
		(layer "F.Cu")
		(at 435.324504 -357.8098 90)
		(property "Reference" "R149"
			(at 0 0 90)
			(layer "F.SilkS")
			(hide yes)
			(effects
				(font
					(size 1.27 1.27)
				)
			)
		)
		(property "Value" "300KR2F-GP"
			(at 0.064008 -3.993896 90)
			(unlocked yes)
			(layer "F.Fab")
			(hide yes)
			(effects
				(font
					(size 1.016 1.016)
					(thickness 0.1524)
				)
			)
		)
		(property "Device Type" "R402H16"
			(at 0.064008 -5.517896 90)
			(unlocked yes)
			(layer "F.Fab")
			(hide yes)
			(effects
				(font
					(size 1.016 1.016)
					(thickness 0.1524)
				)
			)
		)
		(duplicate_pad_numbers_are_jumpers no)
		(fp_line
			(start 0.508 -0.9398)
			(end -0.508 -0.9398)
			(stroke
				(width 0.1524)
				(type default)
			)
			(layer "F.SilkS")
		)
		(fp_line
			(start -0.508 -0.9398)
			(end -0.508 0.9398)
			(stroke
				(width 0.1524)
				(type default)
			)
			(layer "F.SilkS")
		)
		(fp_rect
			(start -0.508 0.9398)
			(end 0.508 -0.9398)
			(stroke
				(width 0)
				(type default)
			)
			(fill no)
			(layer "F.CrtYd")
		)
		(fp_rect
			(start -0.508 0.9398)
			(end 0.508 -0.9398)
			(stroke
				(width 0)
				(type default)
			)
			(fill no)
			(layer "F.Fab")
		)
		(pad "1" smd custom
			(at 0 -0.4445 90)
			(size 0.1397 0.1397)
			(layers "F.Cu" "F.Mask" "F.Paste")
			(net "GATE_FAN3_R")
			(options
				(clearance outline)
				(anchor circle)
			)
			(primitives
				(gr_poly
					(pts
						(arc
							(start -0.1778 -0.2794)
							(mid -0.249642 -0.249642)
							(end -0.2794 -0.1778)
						)
						(arc
							(start -0.2794 0.1778)
							(mid -0.249642 0.249642)
							(end -0.1778 0.2794)
						)
						(arc
							(start 0.1778 0.2794)
							(mid 0.249642 0.249642)
							(end 0.2794 0.1778)
						)
						(arc
							(start 0.2794 -0.1778)
							(mid 0.249642 -0.249642)
							(end 0.1778 -0.2794)
						)
					)
					(width 0)
					(fill yes)
				)
			)
		)
		(pad "2" smd custom
			(at 0 0.4445 90)
			(size 0.1397 0.1397)
			(layers "F.Cu" "F.Mask" "F.Paste")
			(net "P12V_IN")
			(options
				(clearance outline)
				(anchor circle)
			)
			(primitives
				(gr_poly
					(pts
						(arc
							(start -0.1778 -0.2794)
							(mid -0.249642 -0.249642)
							(end -0.2794 -0.1778)
						)
						(arc
							(start -0.2794 0.1778)
							(mid -0.249642 0.249642)
							(end -0.1778 0.2794)
						)
						(arc
							(start 0.1778 0.2794)
							(mid 0.249642 0.249642)
							(end 0.2794 0.1778)
						)
						(arc
							(start 0.2794 -0.1778)
							(mid 0.249642 -0.249642)
							(end 0.1778 -0.2794)
						)
					)
					(width 0)
					(fill yes)
				)
			)
		)
	)
	(footprint ""
		(layer "F.Cu")
		(at 341.300054 -13.999972)
		(property "Reference" ""
			(at 0 0 0)
			(layer "F.SilkS")
			(hide yes)
			(effects
				(font
					(size 1.27 1.27)
				)
			)
		)
		(property "Value" "*"
			(at -6.3373 -0.4572 0)
			(unlocked yes)
			(layer "F.Fab")
			(hide yes)
			(effects
				(font
					(size 1.016 1.016)
					(thickness 0.1524)
				)
			)
		)
		(duplicate_pad_numbers_are_jumpers no)
		(fp_poly
			(pts
				(arc
					(start 5.0673 0)
					(mid -5.0673 0)
					(end 5.0673 0)
				)
			)
			(stroke
				(width 0)
				(type default)
			)
			(fill no)
			(layer "B.CrtYd")
		)
		(fp_poly
			(pts
				(arc
					(start 5.0673 0)
					(mid -5.0673 0)
					(end 5.0673 0)
				)
			)
			(stroke
				(width 0)
				(type default)
			)
			(fill no)
			(layer "F.CrtYd")
		)
		(fp_poly
			(pts
				(arc
					(start 5.0673 0)
					(mid -5.0673 0)
					(end 5.0673 0)
				)
			)
			(stroke
				(width 0)
				(type default)
			)
			(fill no)
			(layer "B.Fab")
		)
		(fp_poly
			(pts
				(arc
					(start 5.0673 0)
					(mid -5.0673 0)
					(end 5.0673 0)
				)
			)
			(stroke
				(width 0)
				(type default)
			)
			(fill no)
			(layer "F.Fab")
		)
		(pad "1" thru_hole circle
			(at 0 0)
			(size 9.525 9.525)
			(drill 3.556)
			(layers "*.Cu" "*.Mask")
			(remove_unused_layers no)
			(net "Net_34")
			(clearance -2.4765)
			(thermal_gap 0.3048)
			(padstack
				(mode front_inner_back)
				(layer "Inner"
					(shape circle)
					(size 3.9624 3.9624)
					(clearance 0.3048)
				)
				(layer "B.Cu"
					(shape circle)
					(size 9.525 9.525)
					(clearance -2.4765)
				)
			)
		)
		(zone
			(layers "F.Cu" "B.Cu" "In1.Cu" "In2.Cu" "In3.Cu" "In4.Cu" "In5.Cu" "In6.Cu")
			(hatch none 0.5)
			(connect_pads
				(clearance 0)
			)
			(min_thickness 0.25)
			(keepout
				(tracks not_allowed)
				(vias allowed)
				(pads allowed)
				(copperpour not_allowed)
				(footprints allowed)
			)
			(placement
				(enabled no)
				(sheetname "")
			)
			(fill
				(thermal_gap 0.5)
				(thermal_bridge_width 0.5)
				(island_removal_mode 0)
			)
			(polygon
				(pts
					(arc
						(start 346.062554 -13.999972)
						(mid 336.537554 -13.999972)
						(end 346.062554 -13.999972)
					)
				)
			)
		)
	)
	(footprint ""
		(layer "F.Cu")
		(at 102.708202 -361.530392 90)
		(property "Reference" "D45"
			(at 0 0 90)
			(layer "F.SilkS")
			(hide yes)
			(effects
				(font
					(size 1.27 1.27)
				)
			)
		)
		(property "Value" "SMCJ14A-13-F-GP"
			(at -4.445 1.1684 90)
			(unlocked yes)
			(layer "F.Fab")
			(hide yes)
			(effects
				(font
					(size 1.016 1.016)
					(thickness 0.1524)
				)
			)
		)
		(property "Device Type" "D795930AKH104"
			(at -4.445 -0.3556 90)
			(unlocked yes)
			(layer "F.Fab")
			(hide yes)
			(effects
				(font
					(size 1.016 1.016)
					(thickness 0.1524)
				)
			)
		)
		(duplicate_pad_numbers_are_jumpers no)
		(fp_line
			(start 3.2004 -4.8641)
			(end -3.2004 -4.8641)
			(stroke
				(width 0.1524)
				(type default)
			)
			(layer "F.SilkS")
		)
		(fp_line
			(start -3.2004 -4.8641)
			(end -3.2004 4.8641)
			(stroke
				(width 0.1524)
				(type default)
			)
			(layer "F.SilkS")
		)
		(fp_line
			(start 3.2004 4.8641)
			(end 3.2004 -4.8641)
			(stroke
				(width 0.1524)
				(type default)
			)
			(layer "F.SilkS")
		)
		(fp_line
			(start -3.2004 4.8641)
			(end 3.2004 4.8641)
			(stroke
				(width 0.1524)
				(type default)
			)
			(layer "F.SilkS")
		)
		(fp_line
			(start 3.2004 5.0419)
			(end -3.2004 5.0419)
			(stroke
				(width 0.508)
				(type default)
			)
			(layer "F.SilkS")
		)
		(fp_poly
			(pts
				(xy -2.9464 3.429) (xy -1.4859 3.429) (xy -1.4859 3.9751) (xy 1.4859 3.9751) (xy 1.4859 3.429) (xy 2.9464 3.429)
				(xy 2.9464 -3.429) (xy 1.4859 -3.429) (xy 1.4859 -3.9751) (xy -1.4859 -3.9751) (xy -1.4859 -3.429)
				(xy -2.9464 -3.429)
			)
			(stroke
				(width 0)
				(type default)
			)
			(fill no)
			(layer "F.CrtYd")
		)
		(fp_poly
			(pts
				(xy -3.4544 4.9403) (xy -3.4544 -4.9403) (xy 3.4544 -4.9403) (xy 3.4544 -3.429) (xy 1.4859 -3.429)
				(xy 1.4859 -3.9751) (xy -1.4859 -3.9751) (xy -1.4859 -3.429) (xy -2.9464 -3.429) (xy -2.9464 3.429)
				(xy -1.4859 3.429) (xy -1.4859 3.9751) (xy 1.4859 3.9751) (xy 1.4859 3.429) (xy 2.9464 3.429) (xy 2.9464 -3.4163)
				(xy 3.4544 -3.4163) (xy 3.4544 4.9403)
			)
			(stroke
				(width 0)
				(type default)
			)
			(fill no)
			(layer "F.CrtYd")
		)
		(fp_rect
			(start -3.4544 4.9403)
			(end 3.4544 -4.9403)
			(stroke
				(width 0)
				(type default)
			)
			(fill no)
			(layer "F.Fab")
		)
		(pad "A" smd rect
			(at 0 -3.592068 90)
			(size 3.2258 2.032)
			(layers "F.Cu" "F.Mask" "F.Paste")
			(net "GND")
		)
		(pad "K" smd rect
			(at 0 3.592068 90)
			(size 3.2258 2.032)
			(layers "F.Cu" "F.Mask" "F.Paste")
			(net "P12V_CLIP")
		)
	)
	(footprint ""
		(layer "F.Cu")
		(at 241.698526 -355.963728 180)
		(property "Reference" "C557"
			(at 0 0 180)
			(layer "F.SilkS")
			(hide yes)
			(effects
				(font
					(size 1.27 1.27)
				)
			)
		)
		(property "Value" "SCD015U25V2KX-GP"
			(at 1.1811 -2.7051 180)
			(unlocked yes)
			(layer "F.Fab")
			(hide yes)
			(effects
				(font
					(size 1.016 1.016)
					(thickness 0.1524)
				)
			)
		)
		(property "Device Type" "C402H22"
			(at 1.1811 -4.2291 180)
			(unlocked yes)
			(layer "F.Fab")
			(hide yes)
			(effects
				(font
					(size 1.016 1.016)
					(thickness 0.1524)
				)
			)
		)
		(duplicate_pad_numbers_are_jumpers no)
		(fp_rect
			(start -0.4318 0.9525)
			(end 0.4318 -0.9525)
			(stroke
				(width 0)
				(type default)
			)
			(fill no)
			(layer "F.CrtYd")
		)
		(fp_rect
			(start -0.4318 0.9525)
			(end 0.4318 -0.9525)
			(stroke
				(width 0)
				(type default)
			)
			(fill no)
			(layer "F.Fab")
		)
		(pad "1" smd custom
			(at 0 -0.4445 180)
			(size 0.1524 0.1524)
			(layers "F.Cu" "F.Mask" "F.Paste")
			(net "MB3_CM_SENSE_P")
			(options
				(clearance outline)
				(anchor circle)
			)
			(primitives
				(gr_poly
					(pts
						(arc
							(start 0.3048 -0.2032)
							(mid 0.275042 -0.275042)
							(end 0.2032 -0.3048)
						)
						(arc
							(start -0.2032 -0.3048)
							(mid -0.275042 -0.275042)
							(end -0.3048 -0.2032)
						)
						(arc
							(start -0.3048 0.2032)
							(mid -0.275042 0.275042)
							(end -0.2032 0.3048)
						)
						(arc
							(start 0.2032 0.3048)
							(mid 0.275042 0.275042)
							(end 0.3048 0.2032)
						)
					)
					(width 0)
					(fill yes)
				)
			)
		)
		(pad "2" smd custom
			(at 0 0.4445 180)
			(size 0.1524 0.1524)
			(layers "F.Cu" "F.Mask" "F.Paste")
			(net "MB3_CM_SENSE_N")
			(options
				(clearance outline)
				(anchor circle)
			)
			(primitives
				(gr_poly
					(pts
						(arc
							(start 0.3048 -0.2032)
							(mid 0.275042 -0.275042)
							(end 0.2032 -0.3048)
						)
						(arc
							(start -0.2032 -0.3048)
							(mid -0.275042 -0.275042)
							(end -0.3048 -0.2032)
						)
						(arc
							(start -0.3048 0.2032)
							(mid -0.275042 0.275042)
							(end -0.2032 0.3048)
						)
						(arc
							(start 0.2032 0.3048)
							(mid 0.275042 0.275042)
							(end 0.3048 0.2032)
						)
					)
					(width 0)
					(fill yes)
				)
			)
		)
	)
	(footprint ""
		(layer "F.Cu")
		(at 49.068228 -117.166898 -90)
		(property "Reference" "R1124"
			(at 0 0 270)
			(layer "F.SilkS")
			(hide yes)
			(effects
				(font
					(size 1.27 1.27)
				)
			)
		)
		(property "Value" "15KR2F-GP"
			(at 0.064008 -3.993896 270)
			(unlocked yes)
			(layer "F.Fab")
			(hide yes)
			(effects
				(font
					(size 1.016 1.016)
					(thickness 0.1524)
				)
			)
		)
		(property "Device Type" "R402H16"
			(at 0.064008 -5.517896 270)
			(unlocked yes)
			(layer "F.Fab")
			(hide yes)
			(effects
				(font
					(size 1.016 1.016)
					(thickness 0.1524)
				)
			)
		)
		(duplicate_pad_numbers_are_jumpers no)
		(fp_line
			(start -0.508 -0.9398)
			(end -0.508 0.9398)
			(stroke
				(width 0.1524)
				(type default)
			)
			(layer "F.SilkS")
		)
		(fp_line
			(start 0.508 -0.9398)
			(end -0.508 -0.9398)
			(stroke
				(width 0.1524)
				(type default)
			)
			(layer "F.SilkS")
		)
		(fp_rect
			(start -0.508 0.9398)
			(end 0.508 -0.9398)
			(stroke
				(width 0)
				(type default)
			)
			(fill no)
			(layer "F.CrtYd")
		)
		(fp_rect
			(start -0.508 0.9398)
			(end 0.508 -0.9398)
			(stroke
				(width 0)
				(type default)
			)
			(fill no)
			(layer "F.Fab")
		)
		(pad "1" smd custom
			(at 0 -0.4445 270)
			(size 0.1397 0.1397)
			(layers "F.Cu" "F.Mask" "F.Paste")
			(net "P5V_B_2_PGOOD")
			(options
				(clearance outline)
				(anchor circle)
			)
			(primitives
				(gr_poly
					(pts
						(arc
							(start -0.1778 -0.2794)
							(mid -0.249642 -0.249642)
							(end -0.2794 -0.1778)
						)
						(arc
							(start -0.2794 0.1778)
							(mid -0.249642 0.249642)
							(end -0.1778 0.2794)
						)
						(arc
							(start 0.1778 0.2794)
							(mid 0.249642 0.249642)
							(end 0.2794 0.1778)
						)
						(arc
							(start 0.2794 -0.1778)
							(mid 0.249642 -0.249642)
							(end 0.1778 -0.2794)
						)
					)
					(width 0)
					(fill yes)
				)
			)
		)
		(pad "2" smd custom
			(at 0 0.4445 270)
			(size 0.1397 0.1397)
			(layers "F.Cu" "F.Mask" "F.Paste")
			(net "GND")
			(options
				(clearance outline)
				(anchor circle)
			)
			(primitives
				(gr_poly
					(pts
						(arc
							(start -0.1778 -0.2794)
							(mid -0.249642 -0.249642)
							(end -0.2794 -0.1778)
						)
						(arc
							(start -0.2794 0.1778)
							(mid -0.249642 0.249642)
							(end -0.1778 0.2794)
						)
						(arc
							(start 0.1778 0.2794)
							(mid 0.249642 0.249642)
							(end 0.2794 0.1778)
						)
						(arc
							(start 0.2794 -0.1778)
							(mid 0.249642 -0.249642)
							(end 0.1778 -0.2794)
						)
					)
					(width 0)
					(fill yes)
				)
			)
		)
	)
	(footprint ""
		(layer "F.Cu")
		(at 354.866702 -132.437124)
		(property "Reference" "VIA40"
			(at 0 0 0)
			(layer "F.SilkS")
			(hide yes)
			(effects
				(font
					(size 1.27 1.27)
				)
			)
		)
		(property "Value" "100OHM-8L-2D36MM-L16-GP"
			(at -3.4036 -0.4572 0)
			(unlocked yes)
			(layer "F.Fab")
			(hide yes)
			(effects
				(font
					(size 1.016 1.016)
					(thickness 0.1524)
				)
			)
		)
		(property "Device Type" "VIA-PCIE-4P-427097"
			(at -3.4036 -1.9812 0)
			(unlocked yes)
			(layer "F.Fab")
			(hide yes)
			(effects
				(font
					(size 1.016 1.016)
					(thickness 0.1524)
				)
			)
		)
		(duplicate_pad_numbers_are_jumpers no)
		(fp_rect
			(start -2.1336 0.4826)
			(end 2.1336 -0.4826)
			(stroke
				(width 0)
				(type default)
			)
			(fill no)
			(layer "F.CrtYd")
		)
		(fp_rect
			(start -2.1336 0.4826)
			(end 2.1336 -0.4826)
			(stroke
				(width 0)
				(type default)
			)
			(fill no)
			(layer "F.Fab")
		)
		(pad "1" thru_hole circle
			(at -1.651 0)
			(size 0.508 0.508)
			(drill 0.254)
			(layers "*.Cu" "*.Mask")
			(remove_unused_layers no)
			(net "GND")
			(clearance 0.2286)
			(thermal_gap 0.2286)
		)
		(pad "2" thru_hole circle
			(at -0.635 0)
			(size 0.508 0.508)
			(drill 0.254)
			(layers "*.Cu" "*.Mask")
			(remove_unused_layers no)
			(net "PHY_DRV_B_TO_SCC_B_19_DP")
			(clearance 0.2286)
			(thermal_gap 0.2286)
		)
		(pad "3" thru_hole circle
			(at 0.635 0)
			(size 0.508 0.508)
			(drill 0.254)
			(layers "*.Cu" "*.Mask")
			(remove_unused_layers no)
			(net "PHY_DRV_B_TO_SCC_B_19_DN")
			(clearance 0.2286)
			(thermal_gap 0.2286)
		)
		(pad "4" thru_hole circle
			(at 1.651 0)
			(size 0.508 0.508)
			(drill 0.254)
			(layers "*.Cu" "*.Mask")
			(remove_unused_layers no)
			(net "GND")
			(clearance 0.2286)
			(thermal_gap 0.2286)
		)
	)
	(footprint ""
		(layer "F.Cu")
		(at 428.2186 -270.5862 -90)
		(property "Reference" "R304"
			(at 0 0 270)
			(layer "F.SilkS")
			(hide yes)
			(effects
				(font
					(size 1.27 1.27)
				)
			)
		)
		(property "Value" "2R6F-GP"
			(at -0.0508 -4.8514 270)
			(unlocked yes)
			(layer "F.Fab")
			(hide yes)
			(effects
				(font
					(size 1.016 1.016)
					(thickness 0.1524)
				)
			)
		)
		(property "Device Type" "R1206H26"
			(at 0 -6.3754 270)
			(unlocked yes)
			(layer "F.Fab")
			(hide yes)
			(effects
				(font
					(size 1.016 1.016)
					(thickness 0.1524)
				)
			)
		)
		(duplicate_pad_numbers_are_jumpers no)
		(fp_line
			(start -1.016 2.2352)
			(end -1.016 -2.2352)
			(stroke
				(width 0.1524)
				(type default)
			)
			(layer "F.SilkS")
		)
		(fp_line
			(start 1.016 2.2352)
			(end -1.016 2.2352)
			(stroke
				(width 0.1524)
				(type default)
			)
			(layer "F.SilkS")
		)
		(fp_line
			(start -1.016 -2.2352)
			(end 1.016 -2.2352)
			(stroke
				(width 0.1524)
				(type default)
			)
			(layer "F.SilkS")
		)
		(fp_line
			(start 1.016 -2.2352)
			(end 1.016 2.2352)
			(stroke
				(width 0.1524)
				(type default)
			)
			(layer "F.SilkS")
		)
		(fp_rect
			(start -1.0922 2.3114)
			(end 1.0922 -2.3114)
			(stroke
				(width 0)
				(type default)
			)
			(fill no)
			(layer "F.CrtYd")
		)
		(fp_poly
			(pts
				(xy -1.0922 -2.3114) (xy 1.0922 -2.3114) (xy 1.0922 2.3114) (xy -1.0922 2.3114)
			)
			(stroke
				(width 0)
				(type default)
			)
			(fill no)
			(layer "F.Fab")
		)
		(pad "1" smd rect
			(at 0 -1.397 270)
			(size 1.651 1.27)
			(layers "F.Cu" "F.Mask" "F.Paste")
			(net "P12V_HDD9")
		)
		(pad "2" smd rect
			(at 0 1.397 270)
			(size 1.651 1.27)
			(layers "F.Cu" "F.Mask" "F.Paste")
			(net "12V_PRE_9")
		)
	)
	(footprint ""
		(layer "F.Cu")
		(at 454.717404 -371.8814)
		(property "Reference" "C713"
			(at 0 0 0)
			(layer "F.SilkS")
			(hide yes)
			(effects
				(font
					(size 1.27 1.27)
				)
			)
		)
		(property "Value" "SCD1U16V2KX-3GP"
			(at 1.1811 -2.7051 0)
			(unlocked yes)
			(layer "F.Fab")
			(hide yes)
			(effects
				(font
					(size 1.016 1.016)
					(thickness 0.1524)
				)
			)
		)
		(property "Device Type" "C402H22"
			(at 1.1811 -4.2291 0)
			(unlocked yes)
			(layer "F.Fab")
			(hide yes)
			(effects
				(font
					(size 1.016 1.016)
					(thickness 0.1524)
				)
			)
		)
		(duplicate_pad_numbers_are_jumpers no)
		(fp_rect
			(start -0.4318 0.9525)
			(end 0.4318 -0.9525)
			(stroke
				(width 0)
				(type default)
			)
			(fill no)
			(layer "F.CrtYd")
		)
		(fp_rect
			(start -0.4318 0.9525)
			(end 0.4318 -0.9525)
			(stroke
				(width 0)
				(type default)
			)
			(fill no)
			(layer "F.Fab")
		)
		(pad "1" smd custom
			(at 0 -0.4445)
			(size 0.1524 0.1524)
			(layers "F.Cu" "F.Mask" "F.Paste")
			(net "P3V3_IN")
			(options
				(clearance outline)
				(anchor circle)
			)
			(primitives
				(gr_poly
					(pts
						(arc
							(start 0.3048 -0.2032)
							(mid 0.275042 -0.275042)
							(end 0.2032 -0.3048)
						)
						(arc
							(start -0.2032 -0.3048)
							(mid -0.275042 -0.275042)
							(end -0.3048 -0.2032)
						)
						(arc
							(start -0.3048 0.2032)
							(mid -0.275042 0.275042)
							(end -0.2032 0.3048)
						)
						(arc
							(start 0.2032 0.3048)
							(mid 0.275042 0.275042)
							(end 0.3048 0.2032)
						)
					)
					(width 0)
					(fill yes)
				)
			)
		)
		(pad "2" smd custom
			(at 0 0.4445)
			(size 0.1524 0.1524)
			(layers "F.Cu" "F.Mask" "F.Paste")
			(net "GND")
			(options
				(clearance outline)
				(anchor circle)
			)
			(primitives
				(gr_poly
					(pts
						(arc
							(start 0.3048 -0.2032)
							(mid 0.275042 -0.275042)
							(end 0.2032 -0.3048)
						)
						(arc
							(start -0.2032 -0.3048)
							(mid -0.275042 -0.275042)
							(end -0.3048 -0.2032)
						)
						(arc
							(start -0.3048 0.2032)
							(mid -0.275042 0.275042)
							(end -0.2032 0.3048)
						)
						(arc
							(start 0.2032 0.3048)
							(mid 0.275042 0.275042)
							(end 0.3048 0.2032)
						)
					)
					(width 0)
					(fill yes)
				)
			)
		)
	)
)
